# S9S_MB_2U (Grand Teton) — schematic netlist excerpt (pin names and nets, part order shuffled) for the footprints in the layout excerpt that follows; sources: Cadence DE-HDL packaged netlist, KiCad conversion of 03242023_DA0F0TMBIJ0_F0T_Motherboard_J_brd_V01_OCP.brd

PR4256  Q_RES  0 5% CHIP  pkg 0402LF  page 296 : A = NC_PVCCD_HV_CPU1_ACSP7 ; B = GND
R664  Q_RES  499 1% CHIP  pkg 0402LF  page 230 : A = PVNN_TERM_CPU1 ; B = I3C_SPD_DDREFGH_CPU1_SCL

(kicad_pcb
	(version 20260206)
	(generator "pcbnew")
	(generator_version "10.0")
	(general
		(thickness 1.6)
		(legacy_teardrops no)
	)
	(paper "A4")
	(title_block
		(title "03242023_DA0F0TMBIJ0_F0T_Motherboard_J_brd_V01_OCP.brd")
		(comment 1 "Grand Teton / footprints 5294-5295 of 6105")
	)
	(layers
		(0 "F.Cu" signal "TOP")
		(4 "In1.Cu" signal "GND")
		(6 "In2.Cu" signal "IN1")
		(8 "In3.Cu" signal "GND1")
		(10 "In4.Cu" signal "IN2")
		(12 "In5.Cu" signal "GND2")
		(14 "In6.Cu" signal "IN3")
		(16 "In7.Cu" signal "GND3")
		(18 "In8.Cu" signal "VCC")
		(20 "In9.Cu" signal "VCC1")
		(22 "In10.Cu" signal "GND4")
		(24 "In11.Cu" signal "IN4")
		(26 "In12.Cu" signal "GND5")
		(28 "In13.Cu" signal "IN5")
		(30 "In14.Cu" signal "GND6")
		(32 "In15.Cu" signal "IN6")
		(34 "In16.Cu" signal "GND7")
		(2 "B.Cu" signal "BOTTOM")
		(9 "F.Adhes" user "F.Adhesive")
		(11 "B.Adhes" user "B.Adhesive")
		(13 "F.Paste" user "Package Geometry/Pastemask Top")
		(15 "B.Paste" user "Package Geometry/Pastemask Bottom")
		(5 "F.SilkS" user "Ref Des/Silkscreen Top")
		(7 "B.SilkS" user "Ref Des/Silkscreen Bottom")
		(1 "F.Mask" user "Board Geometry/Soldermask Top")
		(3 "B.Mask" user "Board Geometry/Soldermask Bottom")
		(17 "Dwgs.User" user "User.Drawings")
		(19 "Cmts.User" user "User.Comments")
		(21 "Eco1.User" user "User.Eco1")
		(23 "Eco2.User" user "User.Eco2")
		(25 "Edge.Cuts" user "Board Geometry/Outline")
		(27 "Margin" user)
		(31 "F.CrtYd" user "Package Geometry/Place Bound Top")
		(29 "B.CrtYd" user "Package Geometry/Place Bound Bottom")
		(35 "F.Fab" user "Ref Des/Assembly Top")
		(33 "B.Fab" user "Ref Des/Assembly Bottom")
	)
	(footprint ""
		(layer "B.Cu")
		(at 28.6766 -162.423348 -90)
		(property "Reference" "PR4256"
			(at 0 0 90)
			(layer "B.SilkS")
			(hide yes)
			(effects
				(font
					(size 1.27 1.27)
				)
				(justify mirror)
			)
		)
		(property "Value" ""
			(at 0 0 90)
			(layer "B.Fab")
			(effects
				(font
					(size 1.27 1.27)
				)
				(justify mirror)
			)
		)
		(duplicate_pad_numbers_are_jumpers no)
		(fp_line
			(start -0.7874 0.4064)
			(end 0.7874 0.4064)
			(stroke
				(width 0.1524)
				(type default)
			)
			(layer "B.SilkS")
		)
		(fp_line
			(start 0.7874 0.4064)
			(end 0.7874 -0.4064)
			(stroke
				(width 0.1524)
				(type default)
			)
			(layer "B.SilkS")
		)
		(fp_line
			(start -0.7874 -0.4064)
			(end -0.7874 0.4064)
			(stroke
				(width 0.1524)
				(type default)
			)
			(layer "B.SilkS")
		)
		(fp_line
			(start 0.7874 -0.4064)
			(end -0.7874 -0.4064)
			(stroke
				(width 0.1524)
				(type default)
			)
			(layer "B.SilkS")
		)
		(fp_line
			(start -0.67945 0.3048)
			(end -0.120396 0.3048)
			(stroke
				(width 0.1)
				(type default)
			)
			(layer "B.Fab")
		)
		(fp_line
			(start -0.120396 0.3048)
			(end -0.120396 0.2794)
			(stroke
				(width 0.1)
				(type default)
			)
			(layer "B.Fab")
		)
		(fp_line
			(start 0.12065 0.3048)
			(end 0.67945 0.3048)
			(stroke
				(width 0.1)
				(type default)
			)
			(layer "B.Fab")
		)
		(fp_line
			(start 0.67945 0.3048)
			(end 0.67945 -0.305054)
			(stroke
				(width 0.1)
				(type default)
			)
			(layer "B.Fab")
		)
		(fp_line
			(start -0.120396 0.2794)
			(end 0.12065 0.2794)
			(stroke
				(width 0.1)
				(type default)
			)
			(layer "B.Fab")
		)
		(fp_line
			(start 0.12065 0.2794)
			(end 0.12065 0.3048)
			(stroke
				(width 0.1)
				(type default)
			)
			(layer "B.Fab")
		)
		(fp_line
			(start -0.12065 -0.2794)
			(end -0.12065 -0.3048)
			(stroke
				(width 0.1)
				(type default)
			)
			(layer "B.Fab")
		)
		(fp_line
			(start 0.12065 -0.2794)
			(end -0.12065 -0.2794)
			(stroke
				(width 0.1)
				(type default)
			)
			(layer "B.Fab")
		)
		(fp_line
			(start -0.67945 -0.3048)
			(end -0.67945 0.3048)
			(stroke
				(width 0.1)
				(type default)
			)
			(layer "B.Fab")
		)
		(fp_line
			(start -0.12065 -0.3048)
			(end -0.67945 -0.3048)
			(stroke
				(width 0.1)
				(type default)
			)
			(layer "B.Fab")
		)
		(fp_line
			(start 0.12065 -0.305054)
			(end 0.12065 -0.2794)
			(stroke
				(width 0.1)
				(type default)
			)
			(layer "B.Fab")
		)
		(fp_line
			(start 0.67945 -0.305054)
			(end 0.12065 -0.305054)
			(stroke
				(width 0.1)
				(type default)
			)
			(layer "B.Fab")
		)
		(pad "1" smd circle
			(at 0.40005 0 90)
			(size 0 0)
			(layers "B.Cu" "B.Mask" "B.Paste")
			(net "NC_PVCCD_HV_CPU1_ACSP7")
		)
		(pad "2" smd circle
			(at -0.40005 0 90)
			(size 0 0)
			(layers "B.Cu" "B.Mask" "B.Paste")
			(net "GND")
		)
	)
	(footprint ""
		(layer "B.Cu")
		(at 151.281638 -190.35522 -90)
		(property "Reference" "R664"
			(at 0 0 90)
			(layer "B.SilkS")
			(hide yes)
			(effects
				(font
					(size 1.27 1.27)
				)
				(justify mirror)
			)
		)
		(property "Value" ""
			(at 0 0 90)
			(layer "B.Fab")
			(effects
				(font
					(size 1.27 1.27)
				)
				(justify mirror)
			)
		)
		(duplicate_pad_numbers_are_jumpers no)
		(fp_line
			(start -0.7874 0.4064)
			(end 0.7874 0.4064)
			(stroke
				(width 0.1524)
				(type default)
			)
			(layer "B.SilkS")
		)
		(fp_line
			(start 0.7874 0.4064)
			(end 0.7874 -0.4064)
			(stroke
				(width 0.1524)
				(type default)
			)
			(layer "B.SilkS")
		)
		(fp_line
			(start -0.7874 -0.4064)
			(end -0.7874 0.4064)
			(stroke
				(width 0.1524)
				(type default)
			)
			(layer "B.SilkS")
		)
		(fp_line
			(start 0.7874 -0.4064)
			(end -0.7874 -0.4064)
			(stroke
				(width 0.1524)
				(type default)
			)
			(layer "B.SilkS")
		)
		(fp_line
			(start -0.67945 0.3048)
			(end -0.120396 0.3048)
			(stroke
				(width 0.1)
				(type default)
			)
			(layer "B.Fab")
		)
		(fp_line
			(start -0.120396 0.3048)
			(end -0.120396 0.2794)
			(stroke
				(width 0.1)
				(type default)
			)
			(layer "B.Fab")
		)
		(fp_line
			(start 0.12065 0.3048)
			(end 0.67945 0.3048)
			(stroke
				(width 0.1)
				(type default)
			)
			(layer "B.Fab")
		)
		(fp_line
			(start 0.67945 0.3048)
			(end 0.67945 -0.305054)
			(stroke
				(width 0.1)
				(type default)
			)
			(layer "B.Fab")
		)
		(fp_line
			(start -0.120396 0.2794)
			(end 0.12065 0.2794)
			(stroke
				(width 0.1)
				(type default)
			)
			(layer "B.Fab")
		)
		(fp_line
			(start 0.12065 0.2794)
			(end 0.12065 0.3048)
			(stroke
				(width 0.1)
				(type default)
			)
			(layer "B.Fab")
		)
		(fp_line
			(start -0.12065 -0.2794)
			(end -0.12065 -0.3048)
			(stroke
				(width 0.1)
				(type default)
			)
			(layer "B.Fab")
		)
		(fp_line
			(start 0.12065 -0.2794)
			(end -0.12065 -0.2794)
			(stroke
				(width 0.1)
				(type default)
			)
			(layer "B.Fab")
		)
		(fp_line
			(start -0.67945 -0.3048)
			(end -0.67945 0.3048)
			(stroke
				(width 0.1)
				(type default)
			)
			(layer "B.Fab")
		)
		(fp_line
			(start -0.12065 -0.3048)
			(end -0.67945 -0.3048)
			(stroke
				(width 0.1)
				(type default)
			)
			(layer "B.Fab")
		)
		(fp_line
			(start 0.12065 -0.305054)
			(end 0.12065 -0.2794)
			(stroke
				(width 0.1)
				(type default)
			)
			(layer "B.Fab")
		)
		(fp_line
			(start 0.67945 -0.305054)
			(end 0.12065 -0.305054)
			(stroke
				(width 0.1)
				(type default)
			)
			(layer "B.Fab")
		)
		(pad "1" smd circle
			(at 0.40005 0 90)
			(size 0 0)
			(layers "B.Cu" "B.Mask" "B.Paste")
			(net "PVNN_TERM_CPU1")
		)
		(pad "2" smd circle
			(at -0.40005 0 90)
			(size 0 0)
			(layers "B.Cu" "B.Mask" "B.Paste")
			(net "I3C_SPD_DDREFGH_CPU1_SCL")
		)
	)
)
